FILE_TYPE = CONNECTIVITY;
{Allegro Design Entry HDL 17.2-2016 S081 (4005846) 1/11/2022}
"PAGE_NUMBER" = 93;
0"NC";
1"M_I_CPU0_SA_CB<7:0>";
2"M_I_CPU0_SA_CA<6:0>";
3"M_I_CPU0_SB_CA<6:0>";
4"M_I_CPU0_SB_CB<7:0>";
5"M_I_CPU0_SA_DQ<31:0>";
6"M_I_CPU0_SB_DQ<31:0>";
7"M_I_CPU0_SA_DQS_DN<9:0>";
8"M_I_CPU0_SA_DQS_DP<9:0>";
9"M_I_CPU0_SB_DQS_DN<9:0>";
10"M_I_CPU0_SB_DQS_DP<9:0>";
11"GND\g";
12"P3V3_STBY\g";
13"I3C_SPD_DDRGL_CPU0_SCL";
14"I3C_SPD_DDRI_CPU0_SCL";
15"I3C_SPD_DDRGL_CPU0_SDA";
16"PWRGD_CHI_CPU0_DIMM";
17"TP_CHI_CPU0_DIMM_RFU_5";
18"TP_CHI_CPU0_DIMM_RFU_1";
19"TP_CHI_CPU0_DIMM_RFU_0";
20"M_I_CPU0_SA_RSP<0>";
21"M_I_CPU0_SB_RSP<0>";
22"PD_CHI_CPU0_DIMM_SAA";
23"TP_CHI_CPU0_DIMM_RFU_4";
24"P12V_MEM_0\g";
25"GND\g";
26"GND\g";
27"M_I_CPU0_SB_DQS_DP<9>";
28"M_I_CPU0_SB_DQS_DN<9>";
29"M_I_CPU0_SA_DQS_DP<9>";
30"M_I_CPU0_SA_DQS_DN<9>";
31"M_I_CPU0_SA_DQS_DP<8>";
32"M_I_CPU0_SA_DQS_DN<8>";
33"M_I_CPU0_SB_DQS_DN<7>";
34"M_I_CPU0_SA_DQS_DP<7>";
35"M_I_CPU0_SB_DQS_DP<6>";
36"M_I_CPU0_SB_DQS_DN<6>";
37"M_I_CPU0_SA_DQS_DN<6>";
38"M_I_CPU0_SB_DQS_DP<5>";
39"M_I_CPU0_SB_DQS_DN<5>";
40"M_I_CPU0_SA_DQS_DP<5>";
41"M_I_CPU0_SA_DQS_DN<5>";
42"M_I_CPU0_SB_DQS_DP<4>";
43"M_I_CPU0_SB_DQS_DN<4>";
44"M_I_CPU0_SA_DQS_DP<4>";
45"M_I_CPU0_SA_DQS_DN<4>";
46"M_I_CPU0_SB_DQS_DP<3>";
47"M_I_CPU0_SB_DQS_DN<3>";
48"M_I_CPU0_SA_DQS_DP<3>";
49"M_I_CPU0_SA_DQS_DN<3>";
50"M_I_CPU0_SB_DQS_DP<2>";
51"M_I_CPU0_SB_DQS_DN<2>";
52"M_I_CPU0_SA_DQS_DP<2>";
53"M_I_CPU0_SA_DQS_DN<2>";
54"M_I_CPU0_SB_DQS_DP<1>";
55"M_I_CPU0_SB_DQS_DN<1>";
56"M_I_CPU0_SA_DQS_DP<1>";
57"M_I_CPU0_SA_DQS_DN<1>";
58"M_I_CPU0_SB_DQS_DP<0>";
59"M_I_CPU0_SB_DQS_DN<0>";
60"M_I_CPU0_SA_DQS_DP<0>";
61"M_I_CPU0_SA_DQS_DN<0>";
62"M_I_CPU0_SB_DQS_DP<7>";
63"M_I_CPU0_SB_DQS_DN<8>";
64"M_I_CPU0_SB_DQS_DP<8>";
65"M_I_CPU0_SA_DQS_DP<6>";
66"M_I_CPU0_SA_DQS_DN<7>";
67"P3V3_STBY\g";
68"TP_CHI_CPU0_DIMM_RFU_2";
69"TP_CHI_CPU0_DIMM_RFU_3";
70"TP_CHI_CPU0_DIMM_RFU_6";
71"M_I_CPU0_RESET_N";
72"M_I_CPU0_SB_PAR";
73"M_I_CPU0_SA_PAR";
74"PD_CHI_CPU0_DIMM_SAA";
75"M_I_CPU0_SB_DQ<0>";
76"M_I_CPU0_SB_DQ<1>";
77"M_I_CPU0_SB_DQ<2>";
78"M_I_CPU0_SB_DQ<3>";
79"M_I_CPU0_SB_DQ<4>";
80"M_I_CPU0_SB_DQ<5>";
81"M_I_CPU0_SB_DQ<6>";
82"M_I_CPU0_SB_DQ<7>";
83"M_I_CPU0_SB_DQ<8>";
84"M_I_CPU0_SB_DQ<9>";
85"M_I_CPU0_SB_DQ<10>";
86"M_I_CPU0_SB_DQ<11>";
87"M_I_CPU0_SB_DQ<12>";
88"M_I_CPU0_SB_DQ<13>";
89"M_I_CPU0_SB_DQ<14>";
90"M_I_CPU0_SB_DQ<15>";
91"M_I_CPU0_SB_DQ<16>";
92"M_I_CPU0_SB_DQ<17>";
93"M_I_CPU0_SB_DQ<18>";
94"M_I_CPU0_SB_DQ<19>";
95"M_I_CPU0_SB_DQ<20>";
96"M_I_CPU0_SB_DQ<21>";
97"M_I_CPU0_SB_DQ<22>";
98"M_I_CPU0_SB_DQ<23>";
99"M_I_CPU0_SB_DQ<24>";
100"M_I_CPU0_SB_DQ<25>";
101"M_I_CPU0_SB_DQ<26>";
102"M_I_CPU0_SB_DQ<27>";
103"M_I_CPU0_SB_DQ<28>";
104"M_I_CPU0_SB_DQ<29>";
105"M_I_CPU0_SB_DQ<30>";
106"M_I_CPU0_SB_DQ<31>";
107"M_I_CPU0_SA_DQ<0>";
108"M_I_CPU0_SA_DQ<1>";
109"M_I_CPU0_SA_DQ<2>";
110"M_I_CPU0_SA_DQ<3>";
111"M_I_CPU0_SA_DQ<4>";
112"M_I_CPU0_SA_DQ<5>";
113"M_I_CPU0_SA_DQ<6>";
114"M_I_CPU0_SA_DQ<7>";
115"M_I_CPU0_SA_DQ<8>";
116"M_I_CPU0_SA_DQ<9>";
117"M_I_CPU0_SA_DQ<10>";
118"M_I_CPU0_SA_DQ<11>";
119"M_I_CPU0_SA_DQ<12>";
120"M_I_CPU0_SA_DQ<13>";
121"M_I_CPU0_SA_DQ<14>";
122"M_I_CPU0_SA_DQ<15>";
123"M_I_CPU0_SA_DQ<16>";
124"M_I_CPU0_SA_DQ<17>";
125"M_I_CPU0_SA_DQ<18>";
126"M_I_CPU0_SA_DQ<19>";
127"M_I_CPU0_SA_DQ<20>";
128"M_I_CPU0_SA_DQ<21>";
129"M_I_CPU0_SA_DQ<22>";
130"M_I_CPU0_SA_DQ<23>";
131"M_I_CPU0_SA_DQ<24>";
132"M_I_CPU0_SA_DQ<25>";
133"M_I_CPU0_SA_DQ<26>";
134"M_I_CPU0_SA_DQ<27>";
135"M_I_CPU0_SA_DQ<28>";
136"M_I_CPU0_SA_DQ<29>";
137"M_I_CPU0_SA_DQ<30>";
138"M_I_CPU0_SB_CS_N<1>";
139"M_I_CPU0_SA_CS_N<1>";
140"M_I_CPU0_SB_CS_N<0>";
141"M_I_CPU0_SA_CS_N<0>";
142"M_I_CPU0_CLK_DP<0>";
143"M_I_CPU0_CLK_DN<0>";
144"M_I_CPU0_SB_CB<0>";
145"M_I_CPU0_SB_CB<1>";
146"M_I_CPU0_SB_CB<2>";
147"M_I_CPU0_SB_CB<3>";
148"M_I_CPU0_SB_CB<4>";
149"M_I_CPU0_SB_CB<5>";
150"M_I_CPU0_SB_CB<6>";
151"M_I_CPU0_SA_CB<0>";
152"M_I_CPU0_SA_CB<2>";
153"M_I_CPU0_SA_CB<3>";
154"M_I_CPU0_SA_CB<5>";
155"M_I_CPU0_SA_CB<6>";
156"M_I_CPU0_SB_CA<6>";
157"M_I_CPU0_SA_CA<6>";
158"M_I_CPU0_SB_CA<5>";
159"M_I_CPU0_SA_CA<5>";
160"M_I_CPU0_SB_CA<4>";
161"M_I_CPU0_SA_CA<4>";
162"M_I_CPU0_SB_CA<3>";
163"M_I_CPU0_SA_CA<3>";
164"M_I_CPU0_SB_CA<2>";
165"M_I_CPU0_SA_CA<2>";
166"M_I_CPU0_SB_CA<1>";
167"M_I_CPU0_SA_CA<1>";
168"M_I_CPU0_SB_CA<0>";
169"M_I_CPU0_SA_CA<0>";
170"M_I_CPU0_ALERT_N";
171"M_I_CPU0_SB_CB<7>";
172"M_I_CPU0_SA_CB<1>";
173"M_I_CPU0_SA_CB<4>";
174"M_I_CPU0_SA_CB<7>";
175"M_I_CPU0_SA_DQ<31>";
176"PWRGD_CHGL_CPU0";
177"GND\g";
178"GND\g";
%"TAP"
"1","(-6000,4250)","0","mstr_standard","I100";
;
CDS_LIB"mstr_standard"
BODY_TYPE"PLUMBING"
HDL_TAP"TRUE";
"B \NAC \NWC"5;
"S \NAC"
BN"7"114;
%"TAP"
"1","(-6000,4300)","0","mstr_standard","I101";
;
CDS_LIB"mstr_standard"
BODY_TYPE"PLUMBING"
HDL_TAP"TRUE";
"B \NAC \NWC"5;
"S \NAC"
BN"8"115;
%"TAP"
"1","(-6000,4350)","0","mstr_standard","I102";
;
CDS_LIB"mstr_standard"
BODY_TYPE"PLUMBING"
HDL_TAP"TRUE";
"B \NAC \NWC"5;
"S \NAC"
BN"9"116;
%"TAP"
"1","(-6000,4450)","0","mstr_standard","I103";
;
CDS_LIB"mstr_standard"
BODY_TYPE"PLUMBING"
HDL_TAP"TRUE";
"B \NAC \NWC"5;
"S \NAC"
BN"11"118;
%"TAP"
"1","(-6000,4400)","0","mstr_standard","I104";
;
CDS_LIB"mstr_standard"
BODY_TYPE"PLUMBING"
HDL_TAP"TRUE";
"B \NAC \NWC"5;
"S \NAC"
BN"10"117;
%"TAP"
"1","(-6000,4500)","0","mstr_standard","I105";
;
CDS_LIB"mstr_standard"
BODY_TYPE"PLUMBING"
HDL_TAP"TRUE";
"B \NAC \NWC"5;
"S \NAC"
BN"12"119;
%"TAP"
"1","(-6000,4550)","0","mstr_standard","I106";
;
CDS_LIB"mstr_standard"
BODY_TYPE"PLUMBING"
HDL_TAP"TRUE";
"B \NAC \NWC"5;
"S \NAC"
BN"13"120;
%"TAP"
"1","(-6000,4600)","0","mstr_standard","I107";
;
CDS_LIB"mstr_standard"
BODY_TYPE"PLUMBING"
HDL_TAP"TRUE";
"B \NAC \NWC"5;
"S \NAC"
BN"14"121;
%"TAP"
"1","(-6000,4700)","0","mstr_standard","I108";
;
CDS_LIB"mstr_standard"
BODY_TYPE"PLUMBING"
HDL_TAP"TRUE";
"B \NAC \NWC"5;
"S \NAC"
BN"16"123;
%"TAP"
"1","(-6000,4650)","0","mstr_standard","I109";
;
CDS_LIB"mstr_standard"
BODY_TYPE"PLUMBING"
HDL_TAP"TRUE";
"B \NAC \NWC"5;
"S \NAC"
BN"15"122;
%"TAP"
"1","(-6000,4800)","0","mstr_standard","I110";
;
CDS_LIB"mstr_standard"
BODY_TYPE"PLUMBING"
HDL_TAP"TRUE";
"B \NAC \NWC"5;
"S \NAC"
BN"18"125;
%"TAP"
"1","(-6000,4750)","0","mstr_standard","I111";
;
CDS_LIB"mstr_standard"
BODY_TYPE"PLUMBING"
HDL_TAP"TRUE";
"B \NAC \NWC"5;
"S \NAC"
BN"17"124;
%"TAP"
"1","(-6000,4850)","0","mstr_standard","I112";
;
CDS_LIB"mstr_standard"
BODY_TYPE"PLUMBING"
HDL_TAP"TRUE";
"B \NAC \NWC"5;
"S \NAC"
BN"19"126;
%"TAP"
"1","(-6000,4950)","0","mstr_standard","I113";
;
CDS_LIB"mstr_standard"
BODY_TYPE"PLUMBING"
HDL_TAP"TRUE";
"B \NAC \NWC"5;
"S \NAC"
BN"21"128;
%"TAP"
"1","(-6000,4900)","0","mstr_standard","I114";
;
CDS_LIB"mstr_standard"
BODY_TYPE"PLUMBING"
HDL_TAP"TRUE";
"B \NAC \NWC"5;
"S \NAC"
BN"20"127;
%"TAP"
"1","(-6000,5000)","0","mstr_standard","I115";
;
CDS_LIB"mstr_standard"
BODY_TYPE"PLUMBING"
HDL_TAP"TRUE";
"B \NAC \NWC"5;
"S \NAC"
BN"22"129;
%"TAP"
"1","(-6000,5050)","0","mstr_standard","I116";
;
CDS_LIB"mstr_standard"
BODY_TYPE"PLUMBING"
HDL_TAP"TRUE";
"B \NAC \NWC"5;
"S \NAC"
BN"23"130;
%"TAP"
"1","(-6000,5150)","0","mstr_standard","I117";
;
CDS_LIB"mstr_standard"
BODY_TYPE"PLUMBING"
HDL_TAP"TRUE";
"B \NAC \NWC"5;
"S \NAC"
BN"25"132;
%"TAP"
"1","(-6000,5100)","0","mstr_standard","I118";
;
CDS_LIB"mstr_standard"
BODY_TYPE"PLUMBING"
HDL_TAP"TRUE";
"B \NAC \NWC"5;
"S \NAC"
BN"24"131;
%"TAP"
"1","(-6000,5200)","0","mstr_standard","I119";
;
CDS_LIB"mstr_standard"
BODY_TYPE"PLUMBING"
HDL_TAP"TRUE";
"B \NAC \NWC"5;
"S \NAC"
BN"26"133;
%"TAP"
"1","(-6000,5350)","0","mstr_standard","I120";
;
CDS_LIB"mstr_standard"
BODY_TYPE"PLUMBING"
HDL_TAP"TRUE";
"B \NAC \NWC"5;
"S \NAC"
BN"29"136;
%"TAP"
"1","(-6000,5300)","0","mstr_standard","I121";
;
CDS_LIB"mstr_standard"
BODY_TYPE"PLUMBING"
HDL_TAP"TRUE";
"B \NAC \NWC"5;
"S \NAC"
BN"28"135;
%"TAP"
"1","(-6000,5250)","0","mstr_standard","I122";
;
CDS_LIB"mstr_standard"
BODY_TYPE"PLUMBING"
HDL_TAP"TRUE";
"B \NAC \NWC"5;
"S \NAC"
BN"27"134;
%"TAP"
"1","(-6000,5400)","0","mstr_standard","I123";
;
CDS_LIB"mstr_standard"
BODY_TYPE"PLUMBING"
HDL_TAP"TRUE";
"B \NAC \NWC"5;
"S \NAC"
BN"30"137;
%"TAP"
"1","(-6000,5450)","0","mstr_standard","I124";
;
CDS_LIB"mstr_standard"
BODY_TYPE"PLUMBING"
HDL_TAP"TRUE";
"B \NAC \NWC"5;
"S \NAC"
BN"31"175;
%"GND"
"1","(-6425,1150)","0","mstr_symbols","I127";
;
BOM_COST"MEM"
CDS_LIB"mstr_symbols"
SIZE"1B"
BODY_TYPE"PLUMBING"
VOLTAGE"0.0"
HDL_POWER"GND";
"A\NAC"178;
%"Q_RES"
"2","(-6425,1300)","0","pure_quanta","I128";
;
LOCATION"R766"
$SEC"1"
CDS_SEC"1"
WATTAGE"1/16W"
MATERIAL"CHIP"
TOLERANCE"1%"
VALUE"23.2K"
PART_NUMBER"TMP_QCS32322FB11"
PACK_TYPE"0402LF"
CDS_LIB"pure_quanta";
"A"
$PN"1"22;
"B"
$PN"2"178;
%"GND"
"1","(-2125,2025)","0","mstr_symbols","I141";
;
CDS_LIB"mstr_symbols"
SIZE"1B"
BODY_TYPE"PLUMBING"
VOLTAGE"0.0"
HDL_POWER"GND";
"A\NAC"25;
%"GND"
"1","(-325,1800)","0","mstr_symbols","I142";
;
CDS_LIB"mstr_symbols"
SIZE"1B"
BODY_TYPE"PLUMBING"
VOLTAGE"0.0"
HDL_POWER"GND";
"A\NAC"26;
%"SCONN288_DDR506112002KQ"
"3","(-1225,3800)","0","pure_quanta","I143";
;
LOCATION"J18"
$SEC"3"
CDS_SEC"3"
VALUE"SCONN288_DDR506112002KQ"
PART_TYPE"SMLF"
MATERIAL"IO"
PART_NUMBER"DFHST8FS479"
CDS_LMAN_SYM_OUTLINE"-450,1800,450,-1750"
NEEDS_NO_SIZE"TRUE"
CDS_LIB"pure_quanta";
"G3"
$PN"G3"26;
"G2"
$PN"G2"26;
"G1"
$PN"G1"26;
"VSS62"
$PN"141"26;
"VSS61"
$PN"139"26;
"VSS60"
$PN"136"26;
"VSS58"
$PN"132"26;
"VSS104"
$PN"240"25;
"VSS102"
$PN"235"25;
"VSS100"
$PN"230"25;
"VIN_BULK2"
$PN"146"24;
"VIN_BULK1"
$PN"145"24;
"VIN_BULK0"
$PN"1"24;
"VSS126"
$PN"288"25;
"VSS125"
$PN"286"25;
"VSS124"
$PN"284"25;
"VSS123"
$PN"281"25;
"VSS122"
$PN"279"25;
"VSS121"
$PN"277"25;
"VSS120"
$PN"275"25;
"VSS119"
$PN"273"25;
"VSS118"
$PN"270"25;
"VSS117"
$PN"268"25;
"VSS116"
$PN"266"25;
"VSS115"
$PN"264"25;
"VSS114"
$PN"262"25;
"VSS113"
$PN"259"25;
"VSS112"
$PN"257"25;
"VSS111"
$PN"255"25;
"VSS110"
$PN"253"25;
"VSS109"
$PN"251"25;
"VSS108"
$PN"248"25;
"VSS107"
$PN"246"25;
"VSS106"
$PN"244"25;
"VSS105"
$PN"242"25;
"VSS103"
$PN"237"25;
"VSS101"
$PN"233"25;
"VSS99"
$PN"228"25;
"VSS98"
$PN"226"25;
"VSS97"
$PN"224"25;
"VSS96"
$PN"222"25;
"VSS95"
$PN"219"25;
"VSS94"
$PN"216"25;
"VSS93"
$PN"214"25;
"VSS92"
$PN"212"25;
"VSS91"
$PN"210"25;
"VSS90"
$PN"208"25;
"VSS89"
$PN"206"25;
"VSS88"
$PN"204"25;
"VSS87"
$PN"202"25;
"VSS86"
$PN"199"25;
"VSS85"
$PN"197"25;
"VSS84"
$PN"195"25;
"VSS83"
$PN"193"25;
"VSS82"
$PN"191"25;
"VSS81"
$PN"188"25;
"VSS80"
$PN"186"25;
"VSS79"
$PN"184"25;
"VSS78"
$PN"182"25;
"VSS77"
$PN"180"25;
"VSS76"
$PN"177"25;
"VSS75"
$PN"175"25;
"VSS74"
$PN"173"25;
"VSS73"
$PN"171"25;
"VSS72"
$PN"169"25;
"VSS71"
$PN"166"25;
"VSS70"
$PN"164"25;
"VSS69"
$PN"162"25;
"VSS68"
$PN"160"25;
"VSS67"
$PN"158"25;
"VSS66"
$PN"155"25;
"VSS65"
$PN"153"25;
"VSS64"
$PN"151"25;
"VSS63"
$PN"143"26;
"VSS59"
$PN"134"26;
"VSS57"
$PN"130"26;
"VSS56"
$PN"128"26;
"VSS55"
$PN"125"26;
"VSS54"
$PN"123"26;
"VSS53"
$PN"121"26;
"VSS52"
$PN"119"26;
"VSS51"
$PN"117"26;
"VSS50"
$PN"114"26;
"VSS49"
$PN"112"26;
"VSS48"
$PN"110"26;
"VSS47"
$PN"108"26;
"VSS46"
$PN"106"26;
"VSS45"
$PN"103"26;
"VSS44"
$PN"101"26;
"VSS43"
$PN"99"26;
"VSS42"
$PN"97"26;
"VSS41"
$PN"95"26;
"VSS40"
$PN"92"26;
"VSS39"
$PN"90"26;
"VSS38"
$PN"88"26;
"VSS37"
$PN"85"26;
"VSS36"
$PN"83"26;
"VSS35"
$PN"81"26;
"VSS34"
$PN"79"26;
"VSS33"
$PN"77"26;
"VSS32"
$PN"75"26;
"VSS31"
$PN"73"26;
"VSS30"
$PN"71"26;
"VSS29"
$PN"69"26;
"VSS28"
$PN"67"26;
"VSS27"
$PN"65"26;
"VSS26"
$PN"63"26;
"VSS25"
$PN"61"26;
"VSS24"
$PN"59"26;
"VSS23"
$PN"57"26;
"VSS22"
$PN"54"26;
"VSS21"
$PN"52"26;
"VSS20"
$PN"50"26;
"VSS19"
$PN"48"26;
"VSS18"
$PN"46"26;
"VSS17"
$PN"43"26;
"VSS16"
$PN"41"26;
"VSS15"
$PN"39"26;
"VSS14"
$PN"37"26;
"VSS13"
$PN"35"26;
"VSS12"
$PN"32"26;
"VSS11"
$PN"30"26;
"VSS10"
$PN"28"26;
"VSS9"
$PN"26"26;
"VSS8"
$PN"24"26;
"VSS7"
$PN"21"26;
"VSS6"
$PN"19"26;
"VSS5"
$PN"17"26;
"VSS4"
$PN"15"26;
"VSS3"
$PN"13"26;
"VSS2"
$PN"10"26;
"VSS1"
$PN"8"26;
"VSS0"
$PN"6"26;
%"Q_CAP"
"1","(-8650,3275)","2","pure_quanta","I185";
;
LOCATION"C120"
$SEC"1"
CDS_SEC"1"
MATERIAL"X7R"
TOLERANCE"10%"
VALUE"0.1UF"
PART_NUMBER"CH4104K1B00"
VOLTAGE"25V"
PACK_TYPE"0402"
BOM_COST"MEM"
CDS_LIB"pure_quanta"
ROOM"MEM_CH_A_CPU0_DIMM1";
"B"
$PN"2"11;
"A"
$PN"1"67;
%"GND"
"1","(-8650,3050)","0","mstr_symbols","I186";
;
BOM_COST"MEM"
SIZE"1B"
CDS_LIB"mstr_symbols"
BODY_TYPE"PLUMBING"
VOLTAGE"0"
ROOM"MEM_EFGH_DECOUPLING_CAPS"
HDL_POWER"GND";
"A\NAC"11;
%"Q_RES"
"1","(-8475,2200)","2","pure_quanta","I188";
;
LOCATION"R299"
$SEC"1"
CDS_SEC"1"
VALUE"0"
BOM_COST"MEM"
CDS_LIB"pure_quanta"
WATTAGE"1/16W"
MATERIAL"CHIP"
TOLERANCE"5%"
PART_NUMBER"CS00002JB38"
PACK_TYPE"0402LF"
ROOM"RST_CPU0_PLD_TO_DIMM";
"B"
$PN"2"176;
"A"
$PN"1"16;
%"Q_RES"
"2","(-8350,2350)","0","pure_quanta","I189";
;
LOCATION"R98"
$SEC"1"
CDS_SEC"1"
WATTAGE"1/16W"
MATERIAL"EMPTY"
TOLERANCE"5%"
VALUE"1K"
PACK_TYPE"0402LF"
BOM_COST"MEM"
CDS_LIB"pure_quanta"
PART_NUMBER"TMP_QCS21002JB34"
ROOM"MEM_CH_A_CPU0_DIMM1";
"A"
$PN"1"12;
"B"
$PN"2"16;
%"VCC_CORE"
"1","(-8350,2525)","0","mstr_symbols","I190";
;
HDL_POWER"P3V3_STBY"
CDS_LIB"mstr_symbols"
VOLTAGE"3.3"
ROOM"PVCCINFAON_CPU0_CTRL";
"A"12;
%"TAP"
"1","(-3450,4100)","0","mstr_standard","I191";
;
CDS_LIB"mstr_standard"
BODY_TYPE"PLUMBING"
HDL_TAP"TRUE";
"B \NAC \NWC"8;
"S \NAC"
BN"5"40;
%"TAP"
"1","(-3250,4450)","0","mstr_standard","I197";
;
CDS_LIB"mstr_standard"
BODY_TYPE"PLUMBING"
HDL_TAP"TRUE";
"B \NAC \NWC"7;
"S \NAC"
BN"9"30;
%"TAP"
"1","(-3250,4350)","0","mstr_standard","I198";
;
CDS_LIB"mstr_standard"
BODY_TYPE"PLUMBING"
HDL_TAP"TRUE";
"B \NAC \NWC"7;
"S \NAC"
BN"8"32;
%"TAP"
"1","(-3450,4400)","0","mstr_standard","I199";
;
CDS_LIB"mstr_standard"
BODY_TYPE"PLUMBING"
HDL_TAP"TRUE";
"B \NAC \NWC"8;
"S \NAC"
BN"8"31;
%"TAP"
"1","(-3450,4500)","0","mstr_standard","I200";
;
CDS_LIB"mstr_standard"
BODY_TYPE"PLUMBING"
HDL_TAP"TRUE";
"B \NAC \NWC"8;
"S \NAC"
BN"9"29;
%"TAP"
"1","(-3250,4250)","0","mstr_standard","I201";
;
CDS_LIB"mstr_standard"
BODY_TYPE"PLUMBING"
HDL_TAP"TRUE";
"B \NAC \NWC"7;
"S \NAC"
BN"7"66;
%"TAP"
"1","(-3250,4150)","0","mstr_standard","I202";
;
CDS_LIB"mstr_standard"
BODY_TYPE"PLUMBING"
HDL_TAP"TRUE";
"B \NAC \NWC"7;
"S \NAC"
BN"6"37;
%"TAP"
"1","(-3250,4050)","0","mstr_standard","I203";
;
CDS_LIB"mstr_standard"
BODY_TYPE"PLUMBING"
HDL_TAP"TRUE";
"B \NAC \NWC"7;
"S \NAC"
BN"5"41;
%"TAP"
"1","(-3250,3950)","0","mstr_standard","I204";
;
CDS_LIB"mstr_standard"
BODY_TYPE"PLUMBING"
HDL_TAP"TRUE";
"B \NAC \NWC"7;
"S \NAC"
BN"4"45;
%"TAP"
"1","(-3250,3850)","0","mstr_standard","I205";
;
CDS_LIB"mstr_standard"
BODY_TYPE"PLUMBING"
HDL_TAP"TRUE";
"B \NAC \NWC"7;
"S \NAC"
BN"3"49;
%"TAP"
"1","(-3250,3750)","0","mstr_standard","I206";
;
CDS_LIB"mstr_standard"
BODY_TYPE"PLUMBING"
HDL_TAP"TRUE";
"B \NAC \NWC"7;
"S \NAC"
BN"2"53;
%"TAP"
"1","(-3250,3650)","0","mstr_standard","I207";
;
CDS_LIB"mstr_standard"
BODY_TYPE"PLUMBING"
HDL_TAP"TRUE";
"B \NAC \NWC"7;
"S \NAC"
BN"1"57;
%"TAP"
"1","(-3250,3400)","0","mstr_standard","I208";
;
CDS_LIB"mstr_standard"
BODY_TYPE"PLUMBING"
HDL_TAP"TRUE";
"B \NAC \NWC"9;
"S \NAC"
BN"9"28;
%"TAP"
"1","(-3250,3550)","0","mstr_standard","I209";
;
CDS_LIB"mstr_standard"
BODY_TYPE"PLUMBING"
HDL_TAP"TRUE";
"B \NAC \NWC"7;
"S \NAC"
BN"0"61;
%"TAP"
"1","(-3450,4300)","0","mstr_standard","I210";
;
CDS_LIB"mstr_standard"
BODY_TYPE"PLUMBING"
HDL_TAP"TRUE";
"B \NAC \NWC"8;
"S \NAC"
BN"7"34;
%"TAP"
"1","(-3450,4200)","0","mstr_standard","I211";
;
CDS_LIB"mstr_standard"
BODY_TYPE"PLUMBING"
HDL_TAP"TRUE";
"B \NAC \NWC"8;
"S \NAC"
BN"6"65;
%"TAP"
"1","(-3450,4000)","0","mstr_standard","I212";
;
CDS_LIB"mstr_standard"
BODY_TYPE"PLUMBING"
HDL_TAP"TRUE";
"B \NAC \NWC"8;
"S \NAC"
BN"4"44;
%"TAP"
"1","(-3450,3900)","0","mstr_standard","I213";
;
CDS_LIB"mstr_standard"
BODY_TYPE"PLUMBING"
HDL_TAP"TRUE";
"B \NAC \NWC"8;
"S \NAC"
BN"3"48;
%"TAP"
"1","(-3450,3700)","0","mstr_standard","I214";
;
CDS_LIB"mstr_standard"
BODY_TYPE"PLUMBING"
HDL_TAP"TRUE";
"B \NAC \NWC"8;
"S \NAC"
BN"1"56;
%"TAP"
"1","(-3450,3800)","0","mstr_standard","I215";
;
CDS_LIB"mstr_standard"
BODY_TYPE"PLUMBING"
HDL_TAP"TRUE";
"B \NAC \NWC"8;
"S \NAC"
BN"2"52;
%"TAP"
"1","(-3450,3600)","0","mstr_standard","I216";
;
CDS_LIB"mstr_standard"
BODY_TYPE"PLUMBING"
HDL_TAP"TRUE";
"B \NAC \NWC"8;
"S \NAC"
BN"0"60;
%"TAP"
"1","(-3450,3350)","0","mstr_standard","I217";
;
CDS_LIB"mstr_standard"
BODY_TYPE"PLUMBING"
HDL_TAP"TRUE";
"B \NAC \NWC"10;
"S \NAC"
BN"8"64;
%"TAP"
"1","(-3450,3450)","0","mstr_standard","I218";
;
CDS_LIB"mstr_standard"
BODY_TYPE"PLUMBING"
HDL_TAP"TRUE";
"B \NAC \NWC"10;
"S \NAC"
BN"9"27;
%"TAP"
"1","(-3250,3300)","0","mstr_standard","I219";
;
CDS_LIB"mstr_standard"
BODY_TYPE"PLUMBING"
HDL_TAP"TRUE";
"B \NAC \NWC"9;
"S \NAC"
BN"8"63;
%"SCONN288_DDR506112002KQ"
"1","(-6850,3700)","0","pure_quanta","I22";
;
LOCATION"J18"
$SEC"1"
CDS_SEC"1"
PART_NUMBER"DFHST8FS479"
MATERIAL"IO"
VALUE"SCONN288_DDR506112002KQ"
PART_TYPE"SMLF"
CDS_LMAN_SYM_OUTLINE"-450,1900,450,-1850"
NEEDS_NO_SIZE"TRUE"
CDS_LIB"pure_quanta";
"PWR_GOOD||FAIL_N"
$PN"147"16;
"DQ31_A"
$PN"194"175;
"CB7_A"
$PN"205"174;
"CB4_A"
$PN"58"173;
"CB1_A"
$PN"53"172;
"CB7_B"
$PN"236"171;
"ALERT_N \B"
$PN"62"170;
"CA0_A"
$PN"66"169;
"CA0_B"
$PN"76"168;
"CA1_A"
$PN"211"167;
"CA1_B"
$PN"221"166;
"CA2_A"
$PN"68"165;
"CA2_B"
$PN"78"164;
"CA3_A"
$PN"213"163;
"CA3_B"
$PN"223"162;
"CA4_A"
$PN"70"161;
"CA4_B"
$PN"80"160;
"CA5_A"
$PN"215"159;
"CA5_B"
$PN"225"158;
"CA6_A"
$PN"72"157;
"CA6_B"
$PN"82"156;
"CB6_A"
$PN"203"155;
"CB5_A"
$PN"60"154;
"CB3_A"
$PN"198"153;
"CB2_A"
$PN"196"152;
"CB0_A"
$PN"51"151;
"CB6_B"
$PN"234"150;
"CB5_B"
$PN"91"149;
"CB4_B"
$PN"89"148;
"CB3_B"
$PN"243"147;
"CB2_B"
$PN"241"146;
"CB1_B"
$PN"98"145;
"CB0_B"
$PN"96"144;
"CK_C \B"
$PN"218"143;
"CK_T"
$PN"217"142;
"CS0_A_N"
$PN"64"141;
"CS0_B_N"
$PN"84"140;
"CS1_A_N"
$PN"209"139;
"CS1_B_N"
$PN"229"138;
"DQ30_A"
$PN"192"137;
"DQ29_A"
$PN"49"136;
"DQ28_A"
$PN"47"135;
"DQ27_A"
$PN"187"134;
"DQ26_A"
$PN"185"133;
"DQ25_A"
$PN"42"132;
"DQ24_A"
$PN"40"131;
"DQ23_A"
$PN"183"130;
"DQ22_A"
$PN"181"129;
"DQ21_A"
$PN"38"128;
"DQ20_A"
$PN"36"127;
"DQ19_A"
$PN"176"126;
"DQ18_A"
$PN"174"125;
"DQ17_A"
$PN"31"124;
"DQ16_A"
$PN"29"123;
"DQ15_A"
$PN"172"122;
"DQ14_A"
$PN"170"121;
"DQ13_A"
$PN"27"120;
"DQ12_A"
$PN"25"119;
"DQ11_A"
$PN"165"118;
"DQ10_A"
$PN"163"117;
"DQ9_A"
$PN"20"116;
"DQ8_A"
$PN"18"115;
"DQ7_A"
$PN"161"114;
"DQ6_A"
$PN"159"113;
"DQ5_A"
$PN"16"112;
"DQ4_A"
$PN"14"111;
"DQ3_A"
$PN"154"110;
"DQ2_A"
$PN"152"109;
"DQ1_A"
$PN"9"108;
"DQ0_A"
$PN"7"107;
"DQ31_B"
$PN"287"106;
"DQ30_B"
$PN"285"105;
"DQ29_B"
$PN"142"104;
"DQ28_B"
$PN"140"103;
"DQ27_B"
$PN"280"102;
"DQ26_B"
$PN"278"101;
"DQ25_B"
$PN"135"100;
"DQ24_B"
$PN"133"99;
"DQ23_B"
$PN"276"98;
"DQ22_B"
$PN"274"97;
"DQ21_B"
$PN"131"96;
"DQ20_B"
$PN"129"95;
"DQ19_B"
$PN"269"94;
"DQ18_B"
$PN"267"93;
"DQ17_B"
$PN"124"92;
"DQ16_B"
$PN"122"91;
"DQ15_B"
$PN"265"90;
"DQ14_B"
$PN"263"89;
"DQ13_B"
$PN"120"88;
"DQ12_B"
$PN"118"87;
"DQ11_B"
$PN"258"86;
"DQ10_B"
$PN"256"85;
"DQ9_B"
$PN"113"84;
"DQ8_B"
$PN"111"83;
"DQ7_B"
$PN"254"82;
"DQ6_B"
$PN"252"81;
"DQ5_B"
$PN"109"80;
"DQ4_B"
$PN"107"79;
"DQ3_B"
$PN"247"78;
"DQ2_B"
$PN"245"77;
"DQ1_B"
$PN"102"76;
"DQ0_B"
$PN"100"75;
"HAS"
$PN"148"74;
"HSCL"
$PN"4"14;
"HSDA"
$PN"5"15;
"LBD||RSP_A_N"
$PN"86"20;
"LBS||RSP_B_N"
$PN"87"21;
"PAR_A"
$PN"74"73;
"PAR_B"
$PN"227"72;
"RESET_N \B"
$PN"207"71;
"RFU6"
$PN"232"70;
"RFU5"
$PN"231"17;
"RFU4"
$PN"220"23;
"RFU3"
$PN"150"69;
"RFU2"
$PN"149"68;
"RFU1"
$PN"144"18;
"RFU0"
$PN"2"19;
"VIN_MGMT"
$PN"3"67;
%"TAP"
"1","(-3250,3200)","0","mstr_standard","I220";
;
CDS_LIB"mstr_standard"
BODY_TYPE"PLUMBING"
HDL_TAP"TRUE";
"B \NAC \NWC"9;
"S \NAC"
BN"7"33;
%"TAP"
"1","(-3250,3100)","0","mstr_standard","I221";
;
CDS_LIB"mstr_standard"
BODY_TYPE"PLUMBING"
HDL_TAP"TRUE";
"B \NAC \NWC"9;
"S \NAC"
BN"6"36;
%"TAP"
"1","(-3250,3000)","0","mstr_standard","I222";
;
CDS_LIB"mstr_standard"
BODY_TYPE"PLUMBING"
HDL_TAP"TRUE";
"B \NAC \NWC"9;
"S \NAC"
BN"5"39;
%"TAP"
"1","(-3250,2900)","0","mstr_standard","I223";
;
CDS_LIB"mstr_standard"
BODY_TYPE"PLUMBING"
HDL_TAP"TRUE";
"B \NAC \NWC"9;
"S \NAC"
BN"4"43;
%"TAP"
"1","(-3250,2800)","0","mstr_standard","I224";
;
CDS_LIB"mstr_standard"
BODY_TYPE"PLUMBING"
HDL_TAP"TRUE";
"B \NAC \NWC"9;
"S \NAC"
BN"3"47;
%"TAP"
"1","(-3250,2700)","0","mstr_standard","I225";
;
CDS_LIB"mstr_standard"
BODY_TYPE"PLUMBING"
HDL_TAP"TRUE";
"B \NAC \NWC"9;
"S \NAC"
BN"2"51;
%"TAP"
"1","(-3250,2600)","0","mstr_standard","I226";
;
CDS_LIB"mstr_standard"
BODY_TYPE"PLUMBING"
HDL_TAP"TRUE";
"B \NAC \NWC"9;
"S \NAC"
BN"1"55;
%"TAP"
"1","(-3250,2500)","0","mstr_standard","I227";
;
CDS_LIB"mstr_standard"
BODY_TYPE"PLUMBING"
HDL_TAP"TRUE";
"B \NAC \NWC"9;
"S \NAC"
BN"0"59;
%"TAP"
"1","(-3450,3150)","0","mstr_standard","I228";
;
CDS_LIB"mstr_standard"
BODY_TYPE"PLUMBING"
HDL_TAP"TRUE";
"B \NAC \NWC"10;
"S \NAC"
BN"6"35;
%"TAP"
"1","(-3450,3250)","0","mstr_standard","I229";
;
CDS_LIB"mstr_standard"
BODY_TYPE"PLUMBING"
HDL_TAP"TRUE";
"B \NAC \NWC"10;
"S \NAC"
BN"7"62;
%"TAP"
"1","(-7700,3350)","2","mstr_standard","I23";
;
CDS_LIB"mstr_standard"
BODY_TYPE"PLUMBING"
HDL_TAP"TRUE";
"B \NAC \NWC"4;
"S \NAC"
BN"2"146;
%"TAP"
"1","(-3450,3050)","0","mstr_standard","I230";
;
CDS_LIB"mstr_standard"
BODY_TYPE"PLUMBING"
HDL_TAP"TRUE";
"B \NAC \NWC"10;
"S \NAC"
BN"5"38;
%"TAP"
"1","(-3450,2950)","0","mstr_standard","I231";
;
CDS_LIB"mstr_standard"
BODY_TYPE"PLUMBING"
HDL_TAP"TRUE";
"B \NAC \NWC"10;
"S \NAC"
BN"4"42;
%"TAP"
"1","(-3450,2850)","0","mstr_standard","I232";
;
CDS_LIB"mstr_standard"
BODY_TYPE"PLUMBING"
HDL_TAP"TRUE";
"B \NAC \NWC"10;
"S \NAC"
BN"3"46;
%"TAP"
"1","(-3450,2650)","0","mstr_standard","I233";
;
CDS_LIB"mstr_standard"
BODY_TYPE"PLUMBING"
HDL_TAP"TRUE";
"B \NAC \NWC"10;
"S \NAC"
BN"1"54;
%"TAP"
"1","(-3450,2750)","0","mstr_standard","I234";
;
CDS_LIB"mstr_standard"
BODY_TYPE"PLUMBING"
HDL_TAP"TRUE";
"B \NAC \NWC"10;
"S \NAC"
BN"2"50;
%"TAP"
"1","(-3450,2550)","0","mstr_standard","I235";
;
CDS_LIB"mstr_standard"
BODY_TYPE"PLUMBING"
HDL_TAP"TRUE";
"B \NAC \NWC"10;
"S \NAC"
BN"0"58;
%"SCONN288_DDR506112002KQ"
"2","(-4400,3500)","0","pure_quanta","I236";
;
LOCATION"J18"
$SEC"2"
CDS_SEC"2"
PART_TYPE"SMLF"
MATERIAL"IO"
VALUE"SCONN288_DDR506112002KQ"
PART_NUMBER"DFHST8FS479"
CDS_LMAN_SYM_OUTLINE"-600,1150,600,-1150"
NEEDS_NO_SIZE"TRUE"
CDS_LIB"pure_quanta";
"DQS7_A_C||TDQS7_A_C \B"
$PN"178"66;
"DQS6_A_T||TDQS6_A_T"
$PN"168"65;
"DQS8_B_T||TDQS8_B_T"
$PN"283"64;
"DQS8_B_C||TDQS8_B_C \B"
$PN"282"63;
"DQS7_B_T||TDQS7_B_T"
$PN"272"62;
"DQS0_A_C \B"
$PN"12"61;
"DQS0_A_T"
$PN"11"60;
"DQS0_B_C \B"
$PN"105"59;
"DQS0_B_T"
$PN"104"58;
"DQS1_A_C \B"
$PN"23"57;
"DQS1_A_T"
$PN"22"56;
"DQS1_B_C \B"
$PN"116"55;
"DQS1_B_T"
$PN"115"54;
"DQS2_A_C \B"
$PN"34"53;
"DQS2_A_T"
$PN"33"52;
"DQS2_B_C \B"
$PN"127"51;
"DQS2_B_T"
$PN"126"50;
"DQS3_A_C \B"
$PN"45"49;
"DQS3_A_T"
$PN"44"48;
"DQS3_B_C \B"
$PN"138"47;
"DQS3_B_T"
$PN"137"46;
"DQS4_A_C \B"
$PN"56"45;
"DQS4_A_T"
$PN"55"44;
"DQS4_B_C \B"
$PN"238"43;
"DQS4_B_T"
$PN"239"42;
"DQS5_A_C||TDQS5_A_C||DQS5_A_T||TDQS5_A_T \B"
$PN"156"41;
"DQS5_A_T||TDQS5_A_T"
$PN"157"40;
"DQS5_B_C||TDQS5_B_C \B"
$PN"249"39;
"DQS5_B_T||TDQS5_B_T"
$PN"250"38;
"DQS6_A_C||TDQS6_A_C||DQS6_A_T||TDQS6_A_T \B"
$PN"167"37;
"DQS6_B_C||TDQS6_B_C \B"
$PN"260"36;
"DQS6_B_T||TDQS6_B_T"
$PN"261"35;
"DQS7_A_T||TDQS7_A_T"
$PN"179"34;
"DQS7_B_C||TDQS7_B_C \B"
$PN"271"33;
"DQS8_A_C||TDQS8_A_C \B"
$PN"189"32;
"DQS8_A_T||TDQS8_A_T"
$PN"190"31;
"DQS9_A_C||TDQS9_A_C \B"
$PN"200"30;
"DQS9_A_T||TDQS9_A_T"
$PN"201"29;
"DQS9_B_C||TDQS9_B_C \B"
$PN"94"28;
"DQS9_B_T||TDQS9_B_T||DBI4_B_N"
$PN"93"27;
%"GND"
"1","(-2825,5550)","0","pure_quanta_power","I237";
;
CDS_LIB"pure_quanta_power"
BOM_COST"MEM"
SIZE"1B"
ROOM"MEM_EFGH_DECOUPLING_CAPS"
HDL_POWER"GND";
"A<SIZE-1..0>\NAC"177;
%"Q_CAP"
"1","(-2825,5900)","2","pure_quanta","I238";
;
LOCATION"C162"
$SEC"1"
CDS_SEC"1"
MATERIAL"X6S"
TOLERANCE"10%"
VALUE"10UF"
PART_NUMBER"CH6104KEA00"
VOLTAGE"25V"
PACK_TYPE"C0805"
BOM_COST"MEM"
CDS_LIB"pure_quanta"
ROOM"MEM_CH_A_CPU0_DIMM1";
"B"
$PN"2"177;
"A"
$PN"1"24;
%"Q_CAP"
"1","(-2250,5900)","2","pure_quanta","I239";
;
LOCATION"C163"
$SEC"1"
CDS_SEC"1"
MATERIAL"X6S"
TOLERANCE"10%"
VALUE"10UF"
PART_NUMBER"CH6104KEA00"
VOLTAGE"25V"
PACK_TYPE"C0805"
BOM_COST"MEM"
CDS_LIB"pure_quanta"
ROOM"MEM_CH_A_CPU0_DIMM1";
"B"
$PN"2"177;
"A"
$PN"1"24;
%"TAP"
"1","(-7700,3400)","2","mstr_standard","I24";
;
CDS_LIB"mstr_standard"
BODY_TYPE"PLUMBING"
HDL_TAP"TRUE";
"B \NAC \NWC"4;
"S \NAC"
BN"3"147;
%"UNIVERSAL_POWER"
"1","(-2825,6225)","0","pure_quanta_power","I240";
;
HDL_POWER"P12V_MEM_0"
BOM_COST"VR_SYSTEM"
CDS_LIB"pure_quanta_power";
"A"24;
%"Q_RES"
"1","(-7750,2750)","0","pure_quanta","I242";
;
$LOCATION"R1576"
CDS_LOCATION"R1576"
$SEC"1"
CDS_SEC"1"
VALUE"49.9"
CDS_LIB"pure_quanta"
MATERIAL"CHIP"
PACK_TYPE"0402LF"
WATTAGE"1/16W"
TOLERANCE"1%"
PART_NUMBER"CS04992FB07";
"B"
$PN"2"14;
"A"
$PN"1"13;
%"TAP"
"1","(-7700,3300)","2","mstr_standard","I25";
;
CDS_LIB"mstr_standard"
BODY_TYPE"PLUMBING"
HDL_TAP"TRUE";
"B \NAC \NWC"4;
"S \NAC"
BN"1"145;
%"TAP"
"1","(-7700,3250)","2","mstr_standard","I26";
;
CDS_LIB"mstr_standard"
BODY_TYPE"PLUMBING"
HDL_TAP"TRUE";
"B \NAC \NWC"4;
"S \NAC"
BN"0"144;
%"TAP"
"1","(-7700,3450)","2","mstr_standard","I27";
;
CDS_LIB"mstr_standard"
BODY_TYPE"PLUMBING"
HDL_TAP"TRUE";
"B \NAC \NWC"4;
"S \NAC"
BN"4"148;
%"TAP"
"1","(-7700,3500)","2","mstr_standard","I28";
;
CDS_LIB"mstr_standard"
BODY_TYPE"PLUMBING"
HDL_TAP"TRUE";
"B \NAC \NWC"4;
"S \NAC"
BN"5"149;
%"TAP"
"1","(-7700,3550)","2","mstr_standard","I29";
;
CDS_LIB"mstr_standard"
BODY_TYPE"PLUMBING"
HDL_TAP"TRUE";
"B \NAC \NWC"4;
"S \NAC"
BN"6"150;
%"TAP"
"1","(-7700,3600)","2","mstr_standard","I30";
;
CDS_LIB"mstr_standard"
BODY_TYPE"PLUMBING"
HDL_TAP"TRUE";
"B \NAC \NWC"4;
"S \NAC"
BN"7"171;
%"TAP"
"1","(-7700,3700)","2","mstr_standard","I31";
;
CDS_LIB"mstr_standard"
BODY_TYPE"PLUMBING"
HDL_TAP"TRUE";
"B \NAC \NWC"1;
"S \NAC"
BN"0"151;
%"TAP"
"1","(-7700,3750)","2","mstr_standard","I32";
;
CDS_LIB"mstr_standard"
BODY_TYPE"PLUMBING"
HDL_TAP"TRUE";
"B \NAC \NWC"1;
"S \NAC"
BN"1"172;
%"TAP"
"1","(-7700,3800)","2","mstr_standard","I33";
;
CDS_LIB"mstr_standard"
BODY_TYPE"PLUMBING"
HDL_TAP"TRUE";
"B \NAC \NWC"1;
"S \NAC"
BN"2"152;
%"TAP"
"1","(-7700,3850)","2","mstr_standard","I34";
;
CDS_LIB"mstr_standard"
BODY_TYPE"PLUMBING"
HDL_TAP"TRUE";
"B \NAC \NWC"1;
"S \NAC"
BN"3"153;
%"TAP"
"1","(-7700,3900)","2","mstr_standard","I35";
;
CDS_LIB"mstr_standard"
BODY_TYPE"PLUMBING"
HDL_TAP"TRUE";
"B \NAC \NWC"1;
"S \NAC"
BN"4"173;
%"TAP"
"1","(-6000,2250)","0","mstr_standard","I36";
;
CDS_LIB"mstr_standard"
BODY_TYPE"PLUMBING"
HDL_TAP"TRUE";
"B \NAC \NWC"6;
"S \NAC"
BN"0"75;
%"TAP"
"1","(-6000,2350)","0","mstr_standard","I37";
;
CDS_LIB"mstr_standard"
BODY_TYPE"PLUMBING"
HDL_TAP"TRUE";
"B \NAC \NWC"6;
"S \NAC"
BN"2"77;
%"TAP"
"1","(-6000,2400)","0","mstr_standard","I38";
;
CDS_LIB"mstr_standard"
BODY_TYPE"PLUMBING"
HDL_TAP"TRUE";
"B \NAC \NWC"6;
"S \NAC"
BN"3"78;
%"TAP"
"1","(-6000,2300)","0","mstr_standard","I39";
;
CDS_LIB"mstr_standard"
BODY_TYPE"PLUMBING"
HDL_TAP"TRUE";
"B \NAC \NWC"6;
"S \NAC"
BN"1"76;
%"TAP"
"1","(-6000,2450)","0","mstr_standard","I40";
;
CDS_LIB"mstr_standard"
BODY_TYPE"PLUMBING"
HDL_TAP"TRUE";
"B \NAC \NWC"6;
"S \NAC"
BN"4"79;
%"TAP"
"1","(-6000,2500)","0","mstr_standard","I41";
;
CDS_LIB"mstr_standard"
BODY_TYPE"PLUMBING"
HDL_TAP"TRUE";
"B \NAC \NWC"6;
"S \NAC"
BN"5"80;
%"TAP"
"1","(-6000,2550)","0","mstr_standard","I42";
;
CDS_LIB"mstr_standard"
BODY_TYPE"PLUMBING"
HDL_TAP"TRUE";
"B \NAC \NWC"6;
"S \NAC"
BN"6"81;
%"TAP"
"1","(-6000,2600)","0","mstr_standard","I43";
;
CDS_LIB"mstr_standard"
BODY_TYPE"PLUMBING"
HDL_TAP"TRUE";
"B \NAC \NWC"6;
"S \NAC"
BN"7"82;
%"TAP"
"1","(-6000,2650)","0","mstr_standard","I44";
;
CDS_LIB"mstr_standard"
BODY_TYPE"PLUMBING"
HDL_TAP"TRUE";
"B \NAC \NWC"6;
"S \NAC"
BN"8"83;
%"TAP"
"1","(-6000,2700)","0","mstr_standard","I45";
;
CDS_LIB"mstr_standard"
BODY_TYPE"PLUMBING"
HDL_TAP"TRUE";
"B \NAC \NWC"6;
"S \NAC"
BN"9"84;
%"TAP"
"1","(-6000,2750)","0","mstr_standard","I46";
;
CDS_LIB"mstr_standard"
BODY_TYPE"PLUMBING"
HDL_TAP"TRUE";
"B \NAC \NWC"6;
"S \NAC"
BN"10"85;
%"TAP"
"1","(-6000,2800)","0","mstr_standard","I47";
;
CDS_LIB"mstr_standard"
BODY_TYPE"PLUMBING"
HDL_TAP"TRUE";
"B \NAC \NWC"6;
"S \NAC"
BN"11"86;
%"TAP"
"1","(-6000,2900)","0","mstr_standard","I48";
;
CDS_LIB"mstr_standard"
BODY_TYPE"PLUMBING"
HDL_TAP"TRUE";
"B \NAC \NWC"6;
"S \NAC"
BN"13"88;
%"TAP"
"1","(-6000,2850)","0","mstr_standard","I49";
;
CDS_LIB"mstr_standard"
BODY_TYPE"PLUMBING"
HDL_TAP"TRUE";
"B \NAC \NWC"6;
"S \NAC"
BN"12"87;
%"TAP"
"1","(-6000,2950)","0","mstr_standard","I50";
;
CDS_LIB"mstr_standard"
BODY_TYPE"PLUMBING"
HDL_TAP"TRUE";
"B \NAC \NWC"6;
"S \NAC"
BN"14"89;
%"TAP"
"1","(-6000,3000)","0","mstr_standard","I51";
;
CDS_LIB"mstr_standard"
BODY_TYPE"PLUMBING"
HDL_TAP"TRUE";
"B \NAC \NWC"6;
"S \NAC"
BN"15"90;
%"TAP"
"1","(-6000,3050)","0","mstr_standard","I52";
;
CDS_LIB"mstr_standard"
BODY_TYPE"PLUMBING"
HDL_TAP"TRUE";
"B \NAC \NWC"6;
"S \NAC"
BN"16"91;
%"TAP"
"1","(-6000,3100)","0","mstr_standard","I53";
;
CDS_LIB"mstr_standard"
BODY_TYPE"PLUMBING"
HDL_TAP"TRUE";
"B \NAC \NWC"6;
"S \NAC"
BN"17"92;
%"TAP"
"1","(-6000,3150)","0","mstr_standard","I54";
;
CDS_LIB"mstr_standard"
BODY_TYPE"PLUMBING"
HDL_TAP"TRUE";
"B \NAC \NWC"6;
"S \NAC"
BN"18"93;
%"TAP"
"1","(-6000,3200)","0","mstr_standard","I55";
;
CDS_LIB"mstr_standard"
BODY_TYPE"PLUMBING"
HDL_TAP"TRUE";
"B \NAC \NWC"6;
"S \NAC"
BN"19"94;
%"TAP"
"1","(-6000,3250)","0","mstr_standard","I56";
;
CDS_LIB"mstr_standard"
BODY_TYPE"PLUMBING"
HDL_TAP"TRUE";
"B \NAC \NWC"6;
"S \NAC"
BN"20"95;
%"TAP"
"1","(-6000,3300)","0","mstr_standard","I57";
;
CDS_LIB"mstr_standard"
BODY_TYPE"PLUMBING"
HDL_TAP"TRUE";
"B \NAC \NWC"6;
"S \NAC"
BN"21"96;
%"TAP"
"1","(-6000,3350)","0","mstr_standard","I58";
;
CDS_LIB"mstr_standard"
BODY_TYPE"PLUMBING"
HDL_TAP"TRUE";
"B \NAC \NWC"6;
"S \NAC"
BN"22"97;
%"TAP"
"1","(-6000,3400)","0","mstr_standard","I59";
;
CDS_LIB"mstr_standard"
BODY_TYPE"PLUMBING"
HDL_TAP"TRUE";
"B \NAC \NWC"6;
"S \NAC"
BN"23"98;
%"TAP"
"1","(-6000,3450)","0","mstr_standard","I60";
;
CDS_LIB"mstr_standard"
BODY_TYPE"PLUMBING"
HDL_TAP"TRUE";
"B \NAC \NWC"6;
"S \NAC"
BN"24"99;
%"TAP"
"1","(-6000,3500)","0","mstr_standard","I61";
;
CDS_LIB"mstr_standard"
BODY_TYPE"PLUMBING"
HDL_TAP"TRUE";
"B \NAC \NWC"6;
"S \NAC"
BN"25"100;
%"TAP"
"1","(-6000,3550)","0","mstr_standard","I62";
;
CDS_LIB"mstr_standard"
BODY_TYPE"PLUMBING"
HDL_TAP"TRUE";
"B \NAC \NWC"6;
"S \NAC"
BN"26"101;
%"TAP"
"1","(-6000,3600)","0","mstr_standard","I63";
;
CDS_LIB"mstr_standard"
BODY_TYPE"PLUMBING"
HDL_TAP"TRUE";
"B \NAC \NWC"6;
"S \NAC"
BN"27"102;
%"TAP"
"1","(-6000,3650)","0","mstr_standard","I64";
;
CDS_LIB"mstr_standard"
BODY_TYPE"PLUMBING"
HDL_TAP"TRUE";
"B \NAC \NWC"6;
"S \NAC"
BN"28"103;
%"TAP"
"1","(-6000,3700)","0","mstr_standard","I65";
;
CDS_LIB"mstr_standard"
BODY_TYPE"PLUMBING"
HDL_TAP"TRUE";
"B \NAC \NWC"6;
"S \NAC"
BN"29"104;
%"TAP"
"1","(-6000,3800)","0","mstr_standard","I66";
;
CDS_LIB"mstr_standard"
BODY_TYPE"PLUMBING"
HDL_TAP"TRUE";
"B \NAC \NWC"6;
"S \NAC"
BN"31"106;
%"TAP"
"1","(-6000,3750)","0","mstr_standard","I67";
;
CDS_LIB"mstr_standard"
BODY_TYPE"PLUMBING"
HDL_TAP"TRUE";
"B \NAC \NWC"6;
"S \NAC"
BN"30"105;
%"TAP"
"1","(-6000,3900)","0","mstr_standard","I68";
;
CDS_LIB"mstr_standard"
BODY_TYPE"PLUMBING"
HDL_TAP"TRUE";
"B \NAC \NWC"5;
"S \NAC"
BN"0"107;
%"TAP"
"1","(-7700,4050)","2","mstr_standard","I77";
;
CDS_LIB"mstr_standard"
BODY_TYPE"PLUMBING"
HDL_TAP"TRUE";
"B \NAC \NWC"1;
"S \NAC"
BN"7"174;
%"TAP"
"1","(-7700,4000)","2","mstr_standard","I78";
;
CDS_LIB"mstr_standard"
BODY_TYPE"PLUMBING"
HDL_TAP"TRUE";
"B \NAC \NWC"1;
"S \NAC"
BN"6"155;
%"TAP"
"1","(-7700,3950)","2","mstr_standard","I79";
;
CDS_LIB"mstr_standard"
BODY_TYPE"PLUMBING"
HDL_TAP"TRUE";
"B \NAC \NWC"1;
"S \NAC"
BN"5"154;
%"TAP"
"1","(-7700,4900)","2","mstr_standard","I80";
;
CDS_LIB"mstr_standard"
BODY_TYPE"PLUMBING"
HDL_TAP"TRUE";
"B \NAC \NWC"3;
"S \NAC"
BN"3"162;
%"TAP"
"1","(-7700,4850)","2","mstr_standard","I81";
;
CDS_LIB"mstr_standard"
BODY_TYPE"PLUMBING"
HDL_TAP"TRUE";
"B \NAC \NWC"3;
"S \NAC"
BN"2"164;
%"TAP"
"1","(-7700,4800)","2","mstr_standard","I82";
;
CDS_LIB"mstr_standard"
BODY_TYPE"PLUMBING"
HDL_TAP"TRUE";
"B \NAC \NWC"3;
"S \NAC"
BN"1"166;
%"TAP"
"1","(-7700,4750)","2","mstr_standard","I83";
;
CDS_LIB"mstr_standard"
BODY_TYPE"PLUMBING"
HDL_TAP"TRUE";
"B \NAC \NWC"3;
"S \NAC"
BN"0"168;
%"TAP"
"1","(-7700,4950)","2","mstr_standard","I84";
;
CDS_LIB"mstr_standard"
BODY_TYPE"PLUMBING"
HDL_TAP"TRUE";
"B \NAC \NWC"3;
"S \NAC"
BN"4"160;
%"TAP"
"1","(-7700,5000)","2","mstr_standard","I85";
;
CDS_LIB"mstr_standard"
BODY_TYPE"PLUMBING"
HDL_TAP"TRUE";
"B \NAC \NWC"3;
"S \NAC"
BN"5"158;
%"TAP"
"1","(-7700,5050)","2","mstr_standard","I86";
;
CDS_LIB"mstr_standard"
BODY_TYPE"PLUMBING"
HDL_TAP"TRUE";
"B \NAC \NWC"3;
"S \NAC"
BN"6"156;
%"TAP"
"1","(-7700,5200)","2","mstr_standard","I87";
;
CDS_LIB"mstr_standard"
BODY_TYPE"PLUMBING"
HDL_TAP"TRUE";
"B \NAC \NWC"2;
"S \NAC"
BN"1"167;
%"TAP"
"1","(-7700,5150)","2","mstr_standard","I88";
;
CDS_LIB"mstr_standard"
BODY_TYPE"PLUMBING"
HDL_TAP"TRUE";
"B \NAC \NWC"2;
"S \NAC"
BN"0"169;
%"TAP"
"1","(-7700,5250)","2","mstr_standard","I89";
;
CDS_LIB"mstr_standard"
BODY_TYPE"PLUMBING"
HDL_TAP"TRUE";
"B \NAC \NWC"2;
"S \NAC"
BN"2"165;
%"VCC_CORE"
"1","(-8550,3475)","0","mstr_symbols","I9";
;
HDL_POWER"P3V3_STBY"
CDS_LIB"mstr_symbols"
VOLTAGE"3.3"
ROOM"PVCCINFAON_CPU0_CTRL";
"A"67;
%"TAP"
"1","(-7700,5300)","2","mstr_standard","I90";
;
CDS_LIB"mstr_standard"
BODY_TYPE"PLUMBING"
HDL_TAP"TRUE";
"B \NAC \NWC"2;
"S \NAC"
BN"3"163;
%"TAP"
"1","(-7700,5350)","2","mstr_standard","I91";
;
CDS_LIB"mstr_standard"
BODY_TYPE"PLUMBING"
HDL_TAP"TRUE";
"B \NAC \NWC"2;
"S \NAC"
BN"4"161;
%"TAP"
"1","(-7700,5450)","2","mstr_standard","I92";
;
CDS_LIB"mstr_standard"
BODY_TYPE"PLUMBING"
HDL_TAP"TRUE";
"B \NAC \NWC"2;
"S \NAC"
BN"6"157;
%"TAP"
"1","(-7700,5400)","2","mstr_standard","I93";
;
CDS_LIB"mstr_standard"
BODY_TYPE"PLUMBING"
HDL_TAP"TRUE";
"B \NAC \NWC"2;
"S \NAC"
BN"5"159;
%"TAP"
"1","(-6000,3950)","0","mstr_standard","I94";
;
CDS_LIB"mstr_standard"
BODY_TYPE"PLUMBING"
HDL_TAP"TRUE";
"B \NAC \NWC"5;
"S \NAC"
BN"1"108;
%"TAP"
"1","(-6000,4000)","0","mstr_standard","I95";
;
CDS_LIB"mstr_standard"
BODY_TYPE"PLUMBING"
HDL_TAP"TRUE";
"B \NAC \NWC"5;
"S \NAC"
BN"2"109;
%"TAP"
"1","(-6000,4050)","0","mstr_standard","I96";
;
CDS_LIB"mstr_standard"
BODY_TYPE"PLUMBING"
HDL_TAP"TRUE";
"B \NAC \NWC"5;
"S \NAC"
BN"3"110;
%"TAP"
"1","(-6000,4200)","0","mstr_standard","I97";
;
CDS_LIB"mstr_standard"
BODY_TYPE"PLUMBING"
HDL_TAP"TRUE";
"B \NAC \NWC"5;
"S \NAC"
BN"6"113;
%"TAP"
"1","(-6000,4100)","0","mstr_standard","I98";
;
CDS_LIB"mstr_standard"
BODY_TYPE"PLUMBING"
HDL_TAP"TRUE";
"B \NAC \NWC"5;
"S \NAC"
BN"4"111;
%"TAP"
"1","(-6000,4150)","0","mstr_standard","I99";
;
CDS_LIB"mstr_standard"
BODY_TYPE"PLUMBING"
HDL_TAP"TRUE";
"B \NAC \NWC"5;
"S \NAC"
BN"5"112;
END.
